# SCM (Grand Teton) — schematic netlist excerpt (pin names and nets, part order shuffled) for the footprints in the layout excerpt that follows; sources: Cadence DE-HDL packaged netlist, KiCad conversion of 12092022_DA0F0TMDCD0_F0T_Management_Board_D_brd_V3_OCP.brd

R303  Q_RES  0 5% CHIP  pkg 0402LF  page 34 : A = SMB_BMC_MM16_R3_SDA ; B = SMB_BMC_MM16_R5_SDA
R738  Q_RES  4.7K 1% CHIP  pkg 0402LF  page 28 : A = P3V3_AUX ; B = LED_POSTCODE_A0

(kicad_pcb
	(version 20260206)
	(generator "pcbnew")
	(generator_version "10.0")
	(general
		(thickness 1.6)
		(legacy_teardrops no)
	)
	(paper "A4")
	(title_block
		(title "12092022_DA0F0TMDCD0_F0T_Management_Board_D_brd_V3_OCP.brd")
		(comment 1 "Grand Teton / footprints 1103-1104 of 1440")
	)
	(layers
		(0 "F.Cu" signal "TOP")
		(4 "In1.Cu" signal "GND")
		(6 "In2.Cu" signal "IN1")
		(8 "In3.Cu" signal "GND1")
		(10 "In4.Cu" signal "IN2")
		(12 "In5.Cu" signal "VCC")
		(14 "In6.Cu" signal "VCC1")
		(16 "In7.Cu" signal "IN3")
		(18 "In8.Cu" signal "GND2")
		(20 "In9.Cu" signal "IN4")
		(22 "In10.Cu" signal "GND3")
		(2 "B.Cu" signal "BOTTOM")
		(9 "F.Adhes" user "F.Adhesive")
		(11 "B.Adhes" user "B.Adhesive")
		(13 "F.Paste" user "Package Geometry/Pastemask Top")
		(15 "B.Paste" user "Package Geometry/Pastemask Bottom")
		(5 "F.SilkS" user "Ref Des/Silkscreen Top")
		(7 "B.SilkS" user "Ref Des/Silkscreen Bottom")
		(1 "F.Mask" user "Board Geometry/Soldermask Top")
		(3 "B.Mask" user "Board Geometry/Soldermask Bottom")
		(17 "Dwgs.User" user "User.Drawings")
		(19 "Cmts.User" user "User.Comments")
		(21 "Eco1.User" user "User.Eco1")
		(23 "Eco2.User" user "User.Eco2")
		(25 "Edge.Cuts" user "Board Geometry/Outline")
		(27 "Margin" user)
		(31 "F.CrtYd" user "Package Geometry/Place Bound Top")
		(29 "B.CrtYd" user "Package Geometry/Place Bound Bottom")
		(35 "F.Fab" user "Ref Des/Assembly Top")
		(33 "B.Fab" user "Ref Des/Assembly Bottom")
	)
	(footprint ""
		(layer "B.Cu")
		(at 56.87568 -95.26524 -90)
		(property "Reference" "R738"
			(at 0 0 90)
			(layer "B.SilkS")
			(hide yes)
			(effects
				(font
					(size 1.27 1.27)
				)
				(justify mirror)
			)
		)
		(property "Value" ""
			(at 0 0 90)
			(layer "B.Fab")
			(effects
				(font
					(size 1.27 1.27)
				)
				(justify mirror)
			)
		)
		(duplicate_pad_numbers_are_jumpers no)
		(fp_line
			(start -0.7874 0.4064)
			(end 0.7874 0.4064)
			(stroke
				(width 0.1524)
				(type default)
			)
			(layer "B.SilkS")
		)
		(fp_line
			(start 0.7874 0.4064)
			(end 0.7874 -0.4064)
			(stroke
				(width 0.1524)
				(type default)
			)
			(layer "B.SilkS")
		)
		(fp_line
			(start -0.7874 -0.4064)
			(end -0.7874 0.4064)
			(stroke
				(width 0.1524)
				(type default)
			)
			(layer "B.SilkS")
		)
		(fp_line
			(start 0.7874 -0.4064)
			(end -0.7874 -0.4064)
			(stroke
				(width 0.1524)
				(type default)
			)
			(layer "B.SilkS")
		)
		(fp_line
			(start -0.67945 0.3048)
			(end -0.120396 0.3048)
			(stroke
				(width 0.1)
				(type default)
			)
			(layer "B.Fab")
		)
		(fp_line
			(start -0.120396 0.3048)
			(end -0.120396 0.2794)
			(stroke
				(width 0.1)
				(type default)
			)
			(layer "B.Fab")
		)
		(fp_line
			(start 0.12065 0.3048)
			(end 0.67945 0.3048)
			(stroke
				(width 0.1)
				(type default)
			)
			(layer "B.Fab")
		)
		(fp_line
			(start 0.67945 0.3048)
			(end 0.67945 -0.305054)
			(stroke
				(width 0.1)
				(type default)
			)
			(layer "B.Fab")
		)
		(fp_line
			(start -0.120396 0.2794)
			(end 0.12065 0.2794)
			(stroke
				(width 0.1)
				(type default)
			)
			(layer "B.Fab")
		)
		(fp_line
			(start 0.12065 0.2794)
			(end 0.12065 0.3048)
			(stroke
				(width 0.1)
				(type default)
			)
			(layer "B.Fab")
		)
		(fp_line
			(start -0.12065 -0.2794)
			(end -0.12065 -0.3048)
			(stroke
				(width 0.1)
				(type default)
			)
			(layer "B.Fab")
		)
		(fp_line
			(start 0.12065 -0.2794)
			(end -0.12065 -0.2794)
			(stroke
				(width 0.1)
				(type default)
			)
			(layer "B.Fab")
		)
		(fp_line
			(start -0.67945 -0.3048)
			(end -0.67945 0.3048)
			(stroke
				(width 0.1)
				(type default)
			)
			(layer "B.Fab")
		)
		(fp_line
			(start -0.12065 -0.3048)
			(end -0.67945 -0.3048)
			(stroke
				(width 0.1)
				(type default)
			)
			(layer "B.Fab")
		)
		(fp_line
			(start 0.12065 -0.305054)
			(end 0.12065 -0.2794)
			(stroke
				(width 0.1)
				(type default)
			)
			(layer "B.Fab")
		)
		(fp_line
			(start 0.67945 -0.305054)
			(end 0.12065 -0.305054)
			(stroke
				(width 0.1)
				(type default)
			)
			(layer "B.Fab")
		)
		(pad "1" smd circle
			(at 0.40005 0 90)
			(size 0 0)
			(layers "B.Cu" "B.Mask" "B.Paste")
			(net "P3V3_AUX")
		)
		(pad "2" smd circle
			(at -0.40005 0 90)
			(size 0 0)
			(layers "B.Cu" "B.Mask" "B.Paste")
			(net "LED_POSTCODE_A0")
		)
	)
	(footprint ""
		(layer "B.Cu")
		(at 18.288 -83.693 90)
		(property "Reference" "R303"
			(at 0 0 90)
			(layer "B.SilkS")
			(hide yes)
			(effects
				(font
					(size 1.27 1.27)
				)
				(justify mirror)
			)
		)
		(property "Value" ""
			(at 0 0 90)
			(layer "B.Fab")
			(effects
				(font
					(size 1.27 1.27)
				)
				(justify mirror)
			)
		)
		(duplicate_pad_numbers_are_jumpers no)
		(fp_line
			(start 0.7874 -0.4064)
			(end -0.7874 -0.4064)
			(stroke
				(width 0.1524)
				(type default)
			)
			(layer "B.SilkS")
		)
		(fp_line
			(start -0.7874 -0.4064)
			(end -0.7874 0.4064)
			(stroke
				(width 0.1524)
				(type default)
			)
			(layer "B.SilkS")
		)
		(fp_line
			(start 0.7874 0.4064)
			(end 0.7874 -0.4064)
			(stroke
				(width 0.1524)
				(type default)
			)
			(layer "B.SilkS")
		)
		(fp_line
			(start -0.7874 0.4064)
			(end 0.7874 0.4064)
			(stroke
				(width 0.1524)
				(type default)
			)
			(layer "B.SilkS")
		)
		(fp_line
			(start 0.67945 -0.305054)
			(end 0.12065 -0.305054)
			(stroke
				(width 0.1)
				(type default)
			)
			(layer "B.Fab")
		)
		(fp_line
			(start 0.12065 -0.305054)
			(end 0.12065 -0.2794)
			(stroke
				(width 0.1)
				(type default)
			)
			(layer "B.Fab")
		)
		(fp_line
			(start -0.12065 -0.3048)
			(end -0.67945 -0.3048)
			(stroke
				(width 0.1)
				(type default)
			)
			(layer "B.Fab")
		)
		(fp_line
			(start -0.67945 -0.3048)
			(end -0.67945 0.3048)
			(stroke
				(width 0.1)
				(type default)
			)
			(layer "B.Fab")
		)
		(fp_line
			(start 0.12065 -0.2794)
			(end -0.12065 -0.2794)
			(stroke
				(width 0.1)
				(type default)
			)
			(layer "B.Fab")
		)
		(fp_line
			(start -0.12065 -0.2794)
			(end -0.12065 -0.3048)
			(stroke
				(width 0.1)
				(type default)
			)
			(layer "B.Fab")
		)
		(fp_line
			(start 0.12065 0.2794)
			(end 0.12065 0.3048)
			(stroke
				(width 0.1)
				(type default)
			)
			(layer "B.Fab")
		)
		(fp_line
			(start -0.120396 0.2794)
			(end 0.12065 0.2794)
			(stroke
				(width 0.1)
				(type default)
			)
			(layer "B.Fab")
		)
		(fp_line
			(start 0.67945 0.3048)
			(end 0.67945 -0.305054)
			(stroke
				(width 0.1)
				(type default)
			)
			(layer "B.Fab")
		)
		(fp_line
			(start 0.12065 0.3048)
			(end 0.67945 0.3048)
			(stroke
				(width 0.1)
				(type default)
			)
			(layer "B.Fab")
		)
		(fp_line
			(start -0.120396 0.3048)
			(end -0.120396 0.2794)
			(stroke
				(width 0.1)
				(type default)
			)
			(layer "B.Fab")
		)
		(fp_line
			(start -0.67945 0.3048)
			(end -0.120396 0.3048)
			(stroke
				(width 0.1)
				(type default)
			)
			(layer "B.Fab")
		)
		(pad "1" smd circle
			(at 0.40005 0 270)
			(size 0 0)
			(layers "B.Cu" "B.Mask" "B.Paste")
			(net "SMB_BMC_MM16_R3_SDA")
		)
		(pad "2" smd circle
			(at -0.40005 0 270)
			(size 0 0)
			(layers "B.Cu" "B.Mask" "B.Paste")
			(net "SMB_BMC_MM16_R5_SDA")
		)
	)
)
